FILE_TYPE = CONNECTIVITY;
{Allegro Design Entry HDL 17.2-2016 S081 (4005846) 1/11/2022}
"PAGE_NUMBER" = 180;
0"NC";
1"GND\g";
2"GND\g";
3"GND\g";
4"GND\g";
5"GND\g";
6"GND\g";
7"GND\g";
8"GND\g";
9"GND\g";
10"GND\g";
11"PVDDCR_CPU1_P0_VCCS"CDS_PHYS_NET_NAME"PVCCIN_CPU0_VREF";
12"PVDDIO_P0_PWM2";
13"PVDDIO_P0_TEMP1";
14"PVDDIO_P0_LSET2";
15"PVDDCR_CPU1_P0_VCCS"CDS_PHYS_NET_NAME"PVCCIN_CPU0_VREF";
16"PVDDIO_P0_IMON2";
17"PVDDIO_P0_VCC2"CDS_PHYS_NET_NAME"PVCCFA_EHV_FIVRA_CPU0_VDD2";
18"PVDDCR_CPU1_P0_PVCC\g";
19"PVDDIO_P0_PWM1";
20"PVDDIO_P0_TEMP1";
21"PVDDIO_P0_LSET1"CDS_PHYS_NET_NAME"PVCCFA_EHV_FIVRA_CPU0_LSET1";
22"PVDDIO_P0_VCC1"CDS_PHYS_NET_NAME"PVCCFA_EHV_FIVRA_CPU0_VDD1";
23"PVDDCR_CPU1_P0_PVCC\g";
24"SW_PVDDIO_P0_BOOTR2";
25"SW_PVDDIO_P0_SW2";
26"P12V_STBY\g";
27"GND\g";
28"GND\g";
29"IND_PVDDIO_P0_CPL2";
30"SW_PVDDIO_P0_BOOTR1";
31"PVDDIO_P0\g";
32"GND\g";
33"IND_PVDDIO_P0_CPL2";
34"SW_PVDDIO_P0_BOOT2_R";
35"IND_PVDDIO_P0_CPL3";
36"SW_PVDDIO_P0_BOOT1";
37"NC_PVDDIO_P0_GL2_1";
38"NC_PVDDIO_P0_GL1_1";
39"GND\g";
40"PVDDIO_P0_IMON1";
41"NC_PVDDIO_P0_DNC1";
42"SW_PVDDIO_P0_BOOT2";
43"SW_P12V_STBY_PVDDIO_P0_FLT\g";
44"SW_PVDDIO_P0_SW1_RC";
45"SW_P12V_STBY_PVDDIO_P0_FLT\g";
46"GND\g";
47"SW_PVDDIO_P0_BOOT1_R";
48"PVDDIO_P0_VOS1";
49"PVDDIO_P0\g";
50"NC_PVDDIO_P0_GL2_2";
51"NC_PVDDIO_P0_GL1_2";
52"SW_PVDDIO_P0_SW2_RC";
53"GND\g";
54"NC_PVDDIO_P0_DNC2";
55"PVDDIO_P0_VOS2";
56"GND\g";
57"PVDDIO_P0\g";
58"SW_PVDDIO_P0_SW1";
59"GND\g";
%"UNIVERSAL_GND"
"1","(825,1550)","0","pure_quanta_power","I1";
;
CDS_LIB"pure_quanta_power"
HDL_POWER"GND";
"A"1;
%"VCC_CORE"
"1","(5425,6350)","0","pure_quanta_power","I100";
;
HDL_POWER"SW_P12V_STBY_PVDDIO_P0_FLT"
CDS_LIB"pure_quanta_power";
"A"45;
%"VCC_CORE"
"1","(5425,3575)","0","pure_quanta_power","I101";
;
HDL_POWER"SW_P12V_STBY_PVDDIO_P0_FLT"
CDS_LIB"pure_quanta_power";
"A"43;
%"Q_CAP"
"1","(225,4700)","0","pure_quanta","I105";
;
LOCATION"PC145_7"
$SEC"1"
CDS_SEC"1"
MATERIAL"X7R"
TOLERANCE"10%"
VALUE"0.1UF"
PART_NUMBER"CH4104K1B00"
VOLTAGE"25V"
PACK_TYPE"0402"
CDS_LIB"pure_quanta";
"B"
$PN"2"7;
"A"
$PN"1"11;
%"Q_CAP"
"1","(250,1900)","0","pure_quanta","I106";
;
LOCATION"PC146_8"
$SEC"1"
CDS_SEC"1"
MATERIAL"X7R"
TOLERANCE"10%"
VALUE"0.1UF"
PART_NUMBER"CH4104K1B00"
VOLTAGE"25V"
PACK_TYPE"0402"
CDS_LIB"pure_quanta";
"B"
$PN"2"8;
"A"
$PN"1"15;
%"Q_RES"
"1","(5425,1250)","0","pure_quanta","I107";
;
LOCATION"PR104"
$SEC"1"
CDS_SEC"1"
WATTAGE"1/16W"
MATERIAL"CHIP"
TOLERANCE"5%"
VALUE"0"
PART_NUMBER"CS00002JB38"
PACK_TYPE"0402LF"
CDS_LIB"pure_quanta";
"B"
$PN"2"49;
"A"
$PN"1"55;
%"Q_RES"
"1","(5425,3975)","0","pure_quanta","I108";
;
LOCATION"PR103"
$SEC"1"
CDS_SEC"1"
PACK_TYPE"0402LF"
MATERIAL"CHIP"
WATTAGE"1/16W"
TOLERANCE"5%"
VALUE"0"
PART_NUMBER"CS00002JB38"
CDS_LIB"pure_quanta";
"B"
$PN"2"57;
"A"
$PN"1"48;
%"Q_CAP"
"1","(4825,5300)","0","pure_quanta","I109";
;
LOCATION"PC155"
$SEC"1"
CDS_SEC"1"
PART_NUMBER"CH4223K1B00"
MATERIAL"X7R"
TOLERANCE"10%"
VALUE"0.22UF"
VOLTAGE"16V"
PACK_TYPE"0402"
CDS_LIB"pure_quanta";
"B"
$PN"2"30;
"A"
$PN"1"47;
%"Q_CAP"
"1","(4825,2500)","0","pure_quanta","I110";
;
LOCATION"PC156"
$SEC"1"
CDS_SEC"1"
PACK_TYPE"0402"
MATERIAL"X7R"
PART_NUMBER"CH4223K1B00"
TOLERANCE"10%"
VALUE"0.22UF"
VOLTAGE"16V"
CDS_LIB"pure_quanta";
"B"
$PN"2"24;
"A"
$PN"1"34;
%"Q_INDUCTOR4P_14"
"1","(6200,2150)","0","pure_quanta","I111";
;
LOCATION"PL18"
$SEC"1"
CDS_SEC"1"
PART_TYPE"SMLF"
PART_NUMBER"CV+15^0TZ04"
MATERIAL"IND"
VALUE"150NH"
CDS_LIB"pure_quanta"
NEEDS_NO_SIZE"TRUE";
"1"
$PN"1"25;
"4"
$PN"4"49;
"3"
$PN"3"33;
"2"
$PN"2"35;
%"Q_INDUCTOR4P_14"
"1","(6025,4950)","0","pure_quanta","I112";
;
LOCATION"PL17"
$SEC"1"
CDS_SEC"1"
PART_TYPE"SMLF"
MATERIAL"IND"
VALUE"150NH"
PART_NUMBER"CV+15^0TZ04"
NEEDS_NO_SIZE"TRUE"
CDS_LIB"pure_quanta";
"1"
$PN"1"58;
"4"
$PN"4"57;
"3"
$PN"3"28;
"2"
$PN"2"29;
%"Q_RES"
"1","(4100,2625)","0","pure_quanta","I113";
;
LOCATION"PR102"
$SEC"1"
CDS_SEC"1"
PACK_TYPE"0402LF"
TOLERANCE"1%"
MATERIAL"CHIP"
WATTAGE"1/16W"
VALUE"4.7"
PART_NUMBER"CS-4702FB19"
CDS_LIB"pure_quanta";
"B"
$PN"2"34;
"A"
$PN"1"42;
%"Q_CAPP"
"1","(5625,6000)","0","pure_quanta","I115";
;
LOCATION"PC164"
$SEC"1"
CDS_SEC"1"
TOLERANCE"20%"
VALUE"220UF"
MATERIAL"OSCON"
PART_NUMBER"CC72204MD02"
VOLTAGE"25V"
PACK_TYPE"THLF"
CDS_LIB"pure_quanta";
"A"
$PN"1"45;
"B"
$PN"2"59;
%"Q_CAPP"
"1","(7125,3275)","0","pure_quanta","I118";
;
LOCATION"PC160"
$SEC"1"
CDS_SEC"1"
PACK_TYPE"SMLF"
PART_NUMBER"CH747LM8825"
MATERIAL"EMPTY"
TOLERANCE"20%"
VALUE"470UF"
VOLTAGE"2.5V"
CDS_LIB"pure_quanta";
"A"
$PN"1"31;
"B"
$PN"2"46;
%"Q_CAP"
"1","(3575,5975)","0","pure_quanta","I119";
;
LOCATION"PC148_1"
$SEC"1"
CDS_SEC"1"
MATERIAL"X7R"
TOLERANCE"10%"
VALUE"0.1UF"
PART_NUMBER"CH4104K1B00"
VOLTAGE"25V"
PACK_TYPE"0402"
CDS_LIB"pure_quanta";
"B"
$PN"2"59;
"A"
$PN"1"45;
%"Q_CAP"
"1","(3650,3200)","0","pure_quanta","I120";
;
LOCATION"PC149_2"
$SEC"1"
CDS_SEC"1"
MATERIAL"X7R"
TOLERANCE"10%"
VALUE"0.1UF"
PART_NUMBER"CH4104K1B00"
VOLTAGE"25V"
PACK_TYPE"0402"
CDS_LIB"pure_quanta";
"B"
$PN"2"56;
"A"
$PN"1"43;
%"Q_CAP"
"1","(1250,5350)","0","pure_quanta","I121";
;
LOCATION"PC143"
$SEC"1"
CDS_SEC"1"
MATERIAL"X6S"
TOLERANCE"10%"
VALUE"2.2UF"
PART_NUMBER"CH5222KEB01"
VOLTAGE"10V"
PACK_TYPE"C0402"
CDS_LIB"pure_quanta";
"B"
$PN"2"2;
"A"
$PN"1"22;
%"UNIVERSAL_GND"
"1","(1250,5150)","0","pure_quanta_power","I122";
;
CDS_LIB"pure_quanta_power"
HDL_POWER"GND";
"A"2;
%"UNIVERSAL_GND"
"1","(1600,5650)","0","pure_quanta_power","I123";
;
CDS_LIB"pure_quanta_power"
HDL_POWER"GND";
"A"3;
%"Q_RES"
"2","(1250,5900)","0","pure_quanta","I124";
;
LOCATION"PR100"
$SEC"1"
CDS_SEC"1"
WATTAGE"1/16W"
MATERIAL"CHIP"
TOLERANCE"1%"
VALUE"2.2"
PART_NUMBER"CS-2202FB00"
PACK_TYPE"0402LF"
CDS_LIB"pure_quanta";
"A"
$PN"1"23;
"B"
$PN"2"22;
%"Q_CAP"
"1","(1600,5925)","0","pure_quanta","I125";
;
LOCATION"PC147_IOP0_1"
$SEC"1"
CDS_SEC"1"
MATERIAL"X6S"
VALUE"2.2UF"
VOLTAGE"10V"
PACK_TYPE"C0402"
TOLERANCE"10%"
PART_NUMBER"CH5222KEB01"
CDS_LIB"pure_quanta";
"B"
$PN"2"3;
"A"
$PN"1"23;
%"Q_CAP"
"1","(1150,2675)","0","pure_quanta","I127";
;
LOCATION"PC142"
$SEC"1"
CDS_SEC"1"
MATERIAL"X6S"
TOLERANCE"10%"
VALUE"2.2UF"
PART_NUMBER"CH5222KEB01"
VOLTAGE"10V"
PACK_TYPE"C0402"
CDS_LIB"pure_quanta";
"B"
$PN"2"4;
"A"
$PN"1"17;
%"UNIVERSAL_GND"
"1","(1150,2475)","0","pure_quanta_power","I128";
;
CDS_LIB"pure_quanta_power"
HDL_POWER"GND";
"A"4;
%"UNIVERSAL_GND"
"1","(1500,2975)","0","pure_quanta_power","I129";
;
CDS_LIB"pure_quanta_power"
HDL_POWER"GND";
"A"5;
%"UNIVERSAL_GND"
"1","(850,4400)","0","pure_quanta_power","I13";
;
CDS_LIB"pure_quanta_power"
HDL_POWER"GND";
"A"6;
%"Q_RES"
"2","(1150,3225)","0","pure_quanta","I130";
;
LOCATION"PR99"
$SEC"1"
CDS_SEC"1"
WATTAGE"1/16W"
MATERIAL"CHIP"
TOLERANCE"1%"
VALUE"2.2"
PART_NUMBER"CS-2202FB00"
PACK_TYPE"0402LF"
CDS_LIB"pure_quanta";
"A"
$PN"1"18;
"B"
$PN"2"17;
%"Q_CAP"
"1","(1500,3250)","0","pure_quanta","I131";
;
LOCATION"PC144_IOP0_2"
$SEC"1"
CDS_SEC"1"
VOLTAGE"10V"
VALUE"2.2UF"
PART_NUMBER"CH5222KEB01"
PACK_TYPE"C0402"
TOLERANCE"10%"
MATERIAL"X6S"
CDS_LIB"pure_quanta";
"B"
$PN"2"5;
"A"
$PN"1"18;
%"UNIVERSAL_GND"
"1","(225,4450)","0","pure_quanta_power","I133";
;
CDS_LIB"pure_quanta_power"
HDL_POWER"GND";
"A"7;
%"UNIVERSAL_GND"
"1","(250,1700)","0","pure_quanta_power","I134";
;
CDS_LIB"pure_quanta_power"
HDL_POWER"GND";
"A"8;
%"UNIVERSAL_GND"
"1","(4300,4100)","0","pure_quanta_power","I136";
;
CDS_LIB"pure_quanta_power"
HDL_POWER"GND";
"A"9;
%"Q_RES"
"2","(4300,4325)","0","pure_quanta","I137";
;
LOCATION"PR221"
$SEC"1"
CDS_SEC"1"
TOLERANCE"1%"
WATTAGE"1/8W"
MATERIAL"EMPTY"
VALUE"1.5"
PART_NUMBER"CS-1504FB00"
PACK_TYPE"0402LF"
CDS_LIB"pure_quanta";
"A"
$PN"1"44;
"B"
$PN"2"9;
%"Q_CAP"
"1","(4300,4875)","0","pure_quanta","I138";
;
LOCATION"PC158"
$SEC"1"
CDS_SEC"1"
MATERIAL"EMPTY"
TOLERANCE"10%"
VALUE"560PF"
PART_NUMBER"CH1566K1B09"
VOLTAGE"50V"
PACK_TYPE"C0402"
CDS_LIB"pure_quanta";
"B"
$PN"2"44;
"A"
$PN"1"58;
%"UNIVERSAL_GND"
"1","(4300,1350)","0","pure_quanta_power","I139";
;
CDS_LIB"pure_quanta_power"
HDL_POWER"GND";
"A"10;
%"Q_RES"
"2","(4300,1575)","0","pure_quanta","I140";
;
LOCATION"PR223"
$SEC"1"
CDS_SEC"1"
WATTAGE"1/8W"
MATERIAL"EMPTY"
TOLERANCE"1%"
VALUE"1.5"
PART_NUMBER"CS-1504FB00"
PACK_TYPE"0402LF"
CDS_LIB"pure_quanta";
"A"
$PN"1"52;
"B"
$PN"2"10;
%"Q_CAP"
"1","(4300,2075)","0","pure_quanta","I141";
;
LOCATION"PC159"
$SEC"1"
CDS_SEC"1"
MATERIAL"EMPTY"
TOLERANCE"10%"
VALUE"560PF"
PART_NUMBER"CH1566K1B09"
VOLTAGE"50V"
PACK_TYPE"C0402"
CDS_LIB"pure_quanta";
"B"
$PN"2"52;
"A"
$PN"1"25;
%"VCC_CORE"
"1","(1250,6325)","0","pure_quanta_power","I142";
;
HDL_POWER"PVDDCR_CPU1_P0_PVCC"
CDS_LIB"pure_quanta_power";
"A"23;
%"VCC_CORE"
"1","(1150,3650)","0","pure_quanta_power","I143";
;
HDL_POWER"PVDDCR_CPU1_P0_PVCC"
CDS_LIB"pure_quanta_power";
"A"18;
%"Q_RES"
"2","(8400,4875)","0","pure_quanta","I144";
;
LOCATION"PR410"
$SEC"1"
CDS_SEC"1"
WATTAGE"1/16W"
MATERIAL"CHIP"
TOLERANCE"1%"
VALUE"1K"
PART_NUMBER"TMP_QCS21002FB24"
PACK_TYPE"0402LF"
CDS_LIB"pure_quanta";
"A"
$PN"1"57;
"B"
$PN"2"27;
%"UNIVERSAL_GND"
"1","(6900,4700)","0","pure_quanta_power","I146";
;
CDS_LIB"pure_quanta_power"
HDL_POWER"GND";
"A"28;
%"Q_RES"
"2","(850,4625)","2","pure_quanta","I17";
;
LOCATION"PR98"
$SEC"1"
CDS_SEC"1"
MATERIAL"EMPTY"
VALUE"8.87K"
PART_NUMBER"CS28872FB01"
PACK_TYPE"0402LF"
WATTAGE"1/16W"
TOLERANCE"1%"
CDS_LIB"pure_quanta";
"A"
$PN"1"21;
"B"
$PN"2"6;
%"Q_RES"
"2","(825,1775)","2","pure_quanta","I2";
;
LOCATION"PR97"
$SEC"1"
CDS_SEC"1"
WATTAGE"1/16W"
MATERIAL"EMPTY"
TOLERANCE"1%"
VALUE"8.87K"
PART_NUMBER"CS28872FB01"
PACK_TYPE"0402LF"
CDS_LIB"pure_quanta";
"A"
$PN"1"14;
"B"
$PN"2"1;
%"ISL99390FRZTR5935"
"1","(2825,2275)","0","pure_quanta","I30";
;
LOCATION"PU18"
$SEC"1"
CDS_SEC"1"
MATERIAL"IC"
PART_TYPE"SMLF"
VALUE"ISL99390FRZ-TR5935"
PART_NUMBER"AL099390004"
CDS_LIB"pure_quanta"
NEEDS_NO_SIZE"TRUE"
CDS_LMAN_SYM_OUTLINE"-300,700,250,-650";
"PGND2"
$PN"7_9-20_24"53;
"GL2"
$PN"41"50;
"GL1"
$PN"6"51;
"DNC"
$PN"31"54;
"EN"
$PN"35"17;
"PGND3"
$PN"40"53;
"VOS"
$PN"1"55;
"VIN2"
$PN"30"43;
"PGND1"
$PN"5"53;
"SW"
$PN"10_19"25;
"LSET"
$PN"37"14;
"IOUT"
$PN"38"16;
"TOUT_FLT"
$PN"36"13;
"PVCC"
$PN"4"18;
"PHASE"
$PN"32"24;
"VIN1"
$PN"25_29"43;
"BOOT"
$PN"33"42;
"AGND"
$PN"2"53;
"VCC"
$PN"3"17;
"REFIN"
$PN"39"15;
"PWM"
$PN"34"12;
%"UNIVERSAL_GND"
"1","(3475,1550)","0","pure_quanta_power","I31";
;
CDS_LIB"pure_quanta_power"
HDL_POWER"GND";
"A"53;
%"UNIVERSAL_GND"
"1","(3475,4350)","0","pure_quanta_power","I34";
;
CDS_LIB"pure_quanta_power"
HDL_POWER"GND";
"A"39;
%"ISL99390FRZTR5935"
"1","(2825,5075)","0","pure_quanta","I35";
;
LOCATION"PU17"
$SEC"1"
CDS_SEC"1"
PART_TYPE"SMLF"
MATERIAL"IC"
VALUE"ISL99390FRZ-TR5935"
PART_NUMBER"AL099390004"
CDS_LIB"pure_quanta"
NEEDS_NO_SIZE"TRUE"
CDS_LMAN_SYM_OUTLINE"-300,700,250,-650";
"PGND2"
$PN"7_9-20_24"39;
"GL2"
$PN"41"37;
"GL1"
$PN"6"38;
"DNC"
$PN"31"41;
"EN"
$PN"35"22;
"PGND3"
$PN"40"39;
"VOS"
$PN"1"48;
"VIN2"
$PN"30"45;
"PGND1"
$PN"5"39;
"SW"
$PN"10_19"58;
"LSET"
$PN"37"21;
"IOUT"
$PN"38"40;
"TOUT_FLT"
$PN"36"20;
"PVCC"
$PN"4"23;
"PHASE"
$PN"32"30;
"VIN1"
$PN"25_29"45;
"BOOT"
$PN"33"36;
"AGND"
$PN"2"39;
"VCC"
$PN"3"22;
"REFIN"
$PN"39"11;
"PWM"
$PN"34"19;
%"Q_CAP"
"1","(4150,3200)","0","pure_quanta","I39";
;
LOCATION"PC151_2"
$SEC"1"
CDS_SEC"1"
MATERIAL"X6S"
TOLERANCE"10%"
VALUE"1UF"
PART_NUMBER"CH5104KEB02"
VOLTAGE"25V"
PACK_TYPE"C0402"
CDS_LIB"pure_quanta";
"B"
$PN"2"56;
"A"
$PN"1"43;
%"Q_CAP"
"1","(4550,3200)","0","pure_quanta","I41";
;
LOCATION"PC153_2"
$SEC"1"
CDS_SEC"1"
MATERIAL"X6S"
TOLERANCE"10%"
VALUE"10UF"
PART_NUMBER"CH6104KEA00"
VOLTAGE"25V"
PACK_TYPE"C0805"
CDS_LIB"pure_quanta";
"B"
$PN"2"56;
"A"
$PN"1"43;
%"Q_CAP"
"1","(4950,3200)","0","pure_quanta","I42";
;
LOCATION"PC157_2"
$SEC"1"
CDS_SEC"1"
MATERIAL"X6S"
TOLERANCE"10%"
VALUE"10UF"
PART_NUMBER"CH6104KEA00"
VOLTAGE"25V"
PACK_TYPE"C0805"
CDS_LIB"pure_quanta";
"B"
$PN"2"56;
"A"
$PN"1"43;
%"UNIVERSAL_GND"
"1","(5425,2850)","0","pure_quanta_power","I44";
;
CDS_LIB"pure_quanta_power"
HDL_POWER"GND";
"A"56;
%"Q_CAP"
"1","(4000,5975)","0","pure_quanta","I50";
;
LOCATION"PC150_1"
$SEC"1"
CDS_SEC"1"
PART_NUMBER"CH5104KEB02"
MATERIAL"X6S"
TOLERANCE"10%"
VALUE"1UF"
VOLTAGE"25V"
PACK_TYPE"C0402"
CDS_LIB"pure_quanta";
"B"
$PN"2"59;
"A"
$PN"1"45;
%"Q_RES"
"1","(3925,5425)","0","pure_quanta","I51";
;
LOCATION"PR101"
$SEC"1"
CDS_SEC"1"
PACK_TYPE"0402LF"
TOLERANCE"1%"
MATERIAL"CHIP"
WATTAGE"1/16W"
VALUE"4.7"
PART_NUMBER"CS-4702FB19"
CDS_LIB"pure_quanta";
"B"
$PN"2"47;
"A"
$PN"1"36;
%"Q_CAP"
"1","(4400,5975)","0","pure_quanta","I52";
;
LOCATION"PC152_1"
$SEC"1"
CDS_SEC"1"
PART_NUMBER"CH6104KEA00"
MATERIAL"X6S"
TOLERANCE"10%"
VALUE"10UF"
VOLTAGE"25V"
PACK_TYPE"C0805"
CDS_LIB"pure_quanta";
"B"
$PN"2"59;
"A"
$PN"1"45;
%"Q_CAP"
"1","(4800,5975)","0","pure_quanta","I56";
;
LOCATION"PC154_1"
$SEC"1"
CDS_SEC"1"
MATERIAL"X6S"
PART_NUMBER"CH6104KEA00"
TOLERANCE"10%"
VALUE"10UF"
VOLTAGE"25V"
PACK_TYPE"C0805"
CDS_LIB"pure_quanta";
"B"
$PN"2"59;
"A"
$PN"1"45;
%"UNIVERSAL_GND"
"1","(5425,5625)","0","pure_quanta_power","I57";
;
CDS_LIB"pure_quanta_power"
HDL_POWER"GND";
"A"59;
%"Q_CAP"
"1","(7625,2075)","0","pure_quanta","I60";
;
LOCATION"PC168_2"
$SEC"1"
CDS_SEC"1"
MATERIAL"X6S"
TOLERANCE"20%"
VALUE"22UF"
PART_NUMBER"TMP_QCH622KMEA01"
VOLTAGE"4V"
PACK_TYPE"0805"
CDS_LIB"pure_quanta";
"B"
$PN"2"32;
"A"
$PN"1"49;
%"Q_CAP"
"1","(8050,2075)","0","pure_quanta","I61";
;
LOCATION"PC170_2"
$SEC"1"
CDS_SEC"1"
MATERIAL"X6S"
TOLERANCE"20%"
VALUE"22UF"
PART_NUMBER"TMP_QCH622KMEA01"
VOLTAGE"4V"
PACK_TYPE"0805"
CDS_LIB"pure_quanta";
"B"
$PN"2"32;
"A"
$PN"1"49;
%"VCC_CORE"
"1","(8050,2425)","0","pure_quanta_power","I64";
;
HDL_POWER"PVDDIO_P0"
CDS_LIB"pure_quanta_power";
"A"49;
%"Q_CAPP"
"1","(7525,3275)","0","pure_quanta","I66";
;
LOCATION"PC162"
$SEC"1"
CDS_SEC"1"
PART_NUMBER"CH747LM8825"
MATERIAL"SPCAP"
TOLERANCE"20%"
VALUE"470UF"
VOLTAGE"2.5V"
PACK_TYPE"SMLF"
CDS_LIB"pure_quanta";
"A"
$PN"1"31;
"B"
$PN"2"46;
%"UNIVERSAL_GND"
"1","(7925,2925)","0","pure_quanta_power","I67";
;
CDS_LIB"pure_quanta_power"
HDL_POWER"GND";
"A"46;
%"Q_CAPP"
"1","(7925,3275)","0","pure_quanta","I68";
;
LOCATION"PC165"
$SEC"1"
CDS_SEC"1"
MATERIAL"SPCAP"
TOLERANCE"20%"
VALUE"470UF"
PART_NUMBER"CH747LM8825"
VOLTAGE"2.5V"
PACK_TYPE"SMLF"
CDS_LIB"pure_quanta";
"A"
$PN"1"31;
"B"
$PN"2"46;
%"VCC_CORE"
"1","(7925,3600)","0","pure_quanta_power","I69";
;
HDL_POWER"PVDDIO_P0"
CDS_LIB"pure_quanta_power";
"A"31;
%"Q_CAP"
"1","(7175,4875)","0","pure_quanta","I70";
;
LOCATION"PC107"
$SEC"1"
CDS_SEC"1"
MATERIAL"X7R"
TOLERANCE"10%"
VALUE"0.1UF"
PART_NUMBER"CH4104K1B00"
VOLTAGE"25V"
PACK_TYPE"0402"
CDS_LIB"pure_quanta";
"B"
$PN"2"27;
"A"
$PN"1"57;
%"VCC_CORE"
"1","(6375,6350)","0","pure_quanta_power","I71";
;
HDL_POWER"P12V_STBY"
CDS_LIB"pure_quanta_power";
"A"26;
%"Q_CAP"
"1","(7675,4875)","0","pure_quanta","I72";
;
LOCATION"PC166_1"
$SEC"1"
CDS_SEC"1"
MATERIAL"X6S"
TOLERANCE"20%"
VALUE"22UF"
PART_NUMBER"TMP_QCH622KMEA01"
VOLTAGE"4V"
PACK_TYPE"0805"
CDS_LIB"pure_quanta";
"B"
$PN"2"27;
"A"
$PN"1"57;
%"Q_CAP"
"1","(8100,4875)","0","pure_quanta","I73";
;
LOCATION"PC169_1"
$SEC"1"
CDS_SEC"1"
MATERIAL"X6S"
TOLERANCE"20%"
VALUE"22UF"
VOLTAGE"4V"
PACK_TYPE"0805"
CDS_LIB"pure_quanta"
PART_NUMBER"TMP_QCH622KMEA01";
"B"
$PN"2"27;
"A"
$PN"1"57;
%"Q_INDUCTOR"
"1","(6050,6250)","0","pure_quanta","I74";
;
LOCATION"PL19"
$SEC"1"
CDS_SEC"1"
MATERIAL"IND"
VALUE"50NH/86A"
PART_NUMBER"CVA50^0MZ09"
PACK_TYPE"SMLF"
NEEDS_NO_SIZE"TRUE"
CDS_LIB"pure_quanta";
"1"
$PN"1"45;
"2"
$PN"2"26;
%"UNIVERSAL_GND"
"1","(8400,4525)","0","pure_quanta_power","I75";
;
CDS_LIB"pure_quanta_power"
HDL_POWER"GND";
"A"27;
%"VCC_CORE"
"1","(8400,5200)","0","pure_quanta_power","I76";
;
HDL_POWER"PVDDIO_P0"
CDS_LIB"pure_quanta_power";
"A"57;
%"UNIVERSAL_GND"
"1","(8050,1725)","0","pure_quanta_power","I80";
;
CDS_LIB"pure_quanta_power"
HDL_POWER"GND";
"A"32;
%"Q_CAP"
"1","(5225,6000)","0","pure_quanta","I85";
;
LOCATION"PC158_1"
$SEC"1"
CDS_SEC"1"
PACK_TYPE"C0805"
PART_NUMBER"CH6104KEA00"
MATERIAL"X6S"
TOLERANCE"10%"
VALUE"10UF"
VOLTAGE"25V"
CDS_LIB"pure_quanta";
"B"
$PN"2"59;
"A"
$PN"1"45;
%"Q_CAP"
"1","(5425,3200)","0","pure_quanta","I86";
;
LOCATION"PC159_2"
$SEC"1"
CDS_SEC"1"
VALUE"10UF"
MATERIAL"X6S"
TOLERANCE"10%"
PART_NUMBER"CH6104KEA00"
VOLTAGE"25V"
PACK_TYPE"C0805"
CDS_LIB"pure_quanta";
"B"
$PN"2"56;
"A"
$PN"1"43;
END.
